# T6G (Grand Teton) — schematic netlist excerpt (pin names and nets, part order shuffled) for the footprints in the layout excerpt that follows; sources: Cadence DE-HDL packaged netlist, KiCad conversion of 04192023_DAF0TMB3IC0_F0TG_MB_C_brd_V02_OCP.brd

R1400  Q_RES  1K 1% CHIP  pkg 0201LF  page 298 : A = JTAG_TRST_RT_CPU0_P2_N ; B = GND
R2786  Q_RES  0 5% CHIP  pkg 0402LF  page 234 : A = USB2_HUB_SWB_DP ; B = USB2_HUB_BUF_SWB_R_DP

PL31  Q_INDUCTOR4P_14  150NH IND  pkg L_TLM117513Q-151QL_11X7-5XA  page 212
  \1\  = SW_PVDDCR_CPU0_P1_SW3
  \2\  = IND_CPU0_P1_CPL2
  \3\  = IND_CPU0_P1_CPL3
  \4\  = PVDDCR_CPU0_P1

(kicad_pcb
	(version 20260206)
	(generator "pcbnew")
	(generator_version "10.0")
	(general
		(thickness 1.6)
		(legacy_teardrops no)
	)
	(paper "A4")
	(title_block
		(title "04192023_DAF0TMB3IC0_F0TG_MB_C_brd_V02_OCP.brd")
		(comment 1 "Grand Teton / footprints 4200-4202 of 8354")
	)
	(layers
		(0 "F.Cu" signal "TOP")
		(4 "In1.Cu" signal "GND")
		(6 "In2.Cu" signal "IN1")
		(8 "In3.Cu" signal "GND1")
		(10 "In4.Cu" signal "IN2")
		(12 "In5.Cu" signal "GND2")
		(14 "In6.Cu" signal "IN3")
		(16 "In7.Cu" signal "GND3")
		(18 "In8.Cu" signal "VCC")
		(20 "In9.Cu" signal "VCC1")
		(22 "In10.Cu" signal "GND4")
		(24 "In11.Cu" signal "IN4")
		(26 "In12.Cu" signal "GND5")
		(28 "In13.Cu" signal "IN5")
		(30 "In14.Cu" signal "GND6")
		(32 "In15.Cu" signal "IN6")
		(34 "In16.Cu" signal "GND7")
		(2 "B.Cu" signal "BOTTOM")
		(9 "F.Adhes" user "F.Adhesive")
		(11 "B.Adhes" user "B.Adhesive")
		(13 "F.Paste" user "Package Geometry/Pastemask Top")
		(15 "B.Paste" user "Package Geometry/Pastemask Bottom")
		(5 "F.SilkS" user "Ref Des/Silkscreen Top")
		(7 "B.SilkS" user "Ref Des/Silkscreen Bottom")
		(1 "F.Mask" user "Board Geometry/Soldermask Top")
		(3 "B.Mask" user "Board Geometry/Soldermask Bottom")
		(17 "Dwgs.User" user "User.Drawings")
		(19 "Cmts.User" user "User.Comments")
		(21 "Eco1.User" user "User.Eco1")
		(23 "Eco2.User" user "User.Eco2")
		(25 "Edge.Cuts" user "Board Geometry/Outline")
		(27 "Margin" user)
		(31 "F.CrtYd" user "Package Geometry/Place Bound Top")
		(29 "B.CrtYd" user "Package Geometry/Place Bound Bottom")
		(35 "F.Fab" user "Ref Des/Assembly Top")
		(33 "B.Fab" user "Ref Des/Assembly Bottom")
	)
	(footprint ""
		(layer "F.Cu")
		(at 98.956114 -192.010284 180)
		(property "Reference" "PL31"
			(at -7.476744 3.583686 90)
			(unlocked yes)
			(layer "F.SilkS")
			(effects
				(font
					(size 0.7874 0.5842)
					(thickness 0.1524)
				)
				(justify left)
			)
		)
		(property "Value" ""
			(at 0 0 180)
			(layer "F.Fab")
			(effects
				(font
					(size 1.27 1.27)
				)
			)
		)
		(duplicate_pad_numbers_are_jumpers no)
		(fp_line
			(start 3.750056 5.500116)
			(end 3.750056 -5.500116)
			(stroke
				(width 0.1524)
				(type default)
			)
			(layer "F.SilkS")
		)
		(fp_line
			(start 3.750056 -5.500116)
			(end 2.393442 -5.500116)
			(stroke
				(width 0.1524)
				(type default)
			)
			(layer "F.SilkS")
		)
		(fp_line
			(start 2.393442 5.500116)
			(end 3.750056 5.500116)
			(stroke
				(width 0.1524)
				(type default)
			)
			(layer "F.SilkS")
		)
		(fp_line
			(start -2.393442 5.500116)
			(end -3.750056 5.500116)
			(stroke
				(width 0.1524)
				(type default)
			)
			(layer "F.SilkS")
		)
		(fp_line
			(start -3.750056 5.500116)
			(end -3.750056 -5.500116)
			(stroke
				(width 0.1524)
				(type default)
			)
			(layer "F.SilkS")
		)
		(fp_line
			(start -3.750056 -5.500116)
			(end -2.393442 -5.500116)
			(stroke
				(width 0.1524)
				(type default)
			)
			(layer "F.SilkS")
		)
		(fp_poly
			(pts
				(xy -3.9116 -4.249928) (xy -4.9276 -3.741928) (xy -4.9276 -4.757928)
			)
			(stroke
				(width 0)
				(type default)
			)
			(fill yes)
			(layer "F.SilkS")
		)
		(fp_line
			(start 3.750056 5.500116)
			(end 3.750056 -5.500116)
			(stroke
				(width 0.1)
				(type default)
			)
			(layer "F.Fab")
		)
		(fp_line
			(start 3.750056 -5.500116)
			(end -3.750056 -5.500116)
			(stroke
				(width 0.1)
				(type default)
			)
			(layer "F.Fab")
		)
		(fp_line
			(start -3.750056 5.500116)
			(end 3.750056 5.500116)
			(stroke
				(width 0.1)
				(type default)
			)
			(layer "F.Fab")
		)
		(fp_line
			(start -3.750056 -5.500116)
			(end -3.750056 5.500116)
			(stroke
				(width 0.1)
				(type default)
			)
			(layer "F.Fab")
		)
		(fp_poly
			(pts
				(xy -4.9276 -4.757928) (xy -4.9276 -3.741928) (xy -3.9116 -4.249928)
			)
			(stroke
				(width 0)
				(type default)
			)
			(fill yes)
			(layer "F.Fab")
		)
		(pad "1" smd rect
			(at 0 -4.249928 90)
			(size 2.413 4.5212)
			(layers "F.Cu" "F.Mask" "F.Paste")
			(net "SW_PVDDCR_CPU0_P1_SW3")
		)
		(pad "2" smd rect
			(at 0 -1.175004 90)
			(size 1.3716 4.5212)
			(layers "F.Cu" "F.Mask" "F.Paste")
			(net "IND_CPU0_P1_CPL2")
		)
		(pad "3" smd rect
			(at 0 1.175004 90)
			(size 1.3716 4.5212)
			(layers "F.Cu" "F.Mask" "F.Paste")
			(net "IND_CPU0_P1_CPL3")
		)
		(pad "4" smd rect
			(at 0 4.249928 90)
			(size 2.413 4.5212)
			(layers "F.Cu" "F.Mask" "F.Paste")
			(net "PVDDCR_CPU0_P1")
		)
	)
	(footprint ""
		(layer "F.Cu")
		(at 436.052722 -408.01036)
		(property "Reference" "R1400"
			(at 0 0 0)
			(layer "F.SilkS")
			(hide yes)
			(effects
				(font
					(size 1.27 1.27)
				)
			)
		)
		(property "Value" ""
			(at 0 0 0)
			(layer "F.Fab")
			(effects
				(font
					(size 1.27 1.27)
				)
			)
		)
		(duplicate_pad_numbers_are_jumpers no)
		(fp_line
			(start -0.32512 -0.175006)
			(end 0.32512 -0.175006)
			(stroke
				(width 0.1)
				(type default)
			)
			(layer "F.Fab")
		)
		(fp_line
			(start -0.32512 0.175006)
			(end -0.32512 -0.175006)
			(stroke
				(width 0.1)
				(type default)
			)
			(layer "F.Fab")
		)
		(fp_line
			(start 0.32512 -0.175006)
			(end 0.32512 0.175006)
			(stroke
				(width 0.1)
				(type default)
			)
			(layer "F.Fab")
		)
		(fp_line
			(start 0.32512 0.175006)
			(end -0.32512 0.175006)
			(stroke
				(width 0.1)
				(type default)
			)
			(layer "F.Fab")
		)
		(pad "1" smd rect
			(at -0.2667 0)
			(size 0.3048 0.381)
			(layers "F.Cu" "F.Mask" "F.Paste")
			(net "JTAG_TRST_RT_CPU0_P2_N")
		)
		(pad "2" smd rect
			(at 0.2667 0 180)
			(size 0.3048 0.381)
			(layers "F.Cu" "F.Mask" "F.Paste")
			(net "GND")
		)
	)
	(footprint ""
		(layer "F.Cu")
		(at 11.421618 -105.48239 90)
		(property "Reference" "R2786"
			(at 0 0 90)
			(layer "F.SilkS")
			(hide yes)
			(effects
				(font
					(size 1.27 1.27)
				)
			)
		)
		(property "Value" ""
			(at 0 0 90)
			(layer "F.Fab")
			(effects
				(font
					(size 1.27 1.27)
				)
			)
		)
		(duplicate_pad_numbers_are_jumpers no)
		(fp_line
			(start 0.7874 -0.4064)
			(end 0.7874 0.4064)
			(stroke
				(width 0.1524)
				(type default)
			)
			(layer "F.SilkS")
		)
		(fp_line
			(start -0.7874 -0.4064)
			(end 0.7874 -0.4064)
			(stroke
				(width 0.1524)
				(type default)
			)
			(layer "F.SilkS")
		)
		(fp_line
			(start 0.7874 0.4064)
			(end -0.7874 0.4064)
			(stroke
				(width 0.1524)
				(type default)
			)
			(layer "F.SilkS")
		)
		(fp_line
			(start -0.7874 0.4064)
			(end -0.7874 -0.4064)
			(stroke
				(width 0.1524)
				(type default)
			)
			(layer "F.SilkS")
		)
		(fp_line
			(start -0.12065 -0.305054)
			(end -0.12065 -0.2794)
			(stroke
				(width 0.1)
				(type default)
			)
			(layer "F.Fab")
		)
		(fp_line
			(start -0.67945 -0.305054)
			(end -0.12065 -0.305054)
			(stroke
				(width 0.1)
				(type default)
			)
			(layer "F.Fab")
		)
		(fp_line
			(start 0.67945 -0.3048)
			(end 0.67945 0.3048)
			(stroke
				(width 0.1)
				(type default)
			)
			(layer "F.Fab")
		)
		(fp_line
			(start 0.12065 -0.3048)
			(end 0.67945 -0.3048)
			(stroke
				(width 0.1)
				(type default)
			)
			(layer "F.Fab")
		)
		(fp_line
			(start 0.12065 -0.2794)
			(end 0.12065 -0.3048)
			(stroke
				(width 0.1)
				(type default)
			)
			(layer "F.Fab")
		)
		(fp_line
			(start -0.12065 -0.2794)
			(end 0.12065 -0.2794)
			(stroke
				(width 0.1)
				(type default)
			)
			(layer "F.Fab")
		)
		(fp_line
			(start 0.120396 0.2794)
			(end -0.12065 0.2794)
			(stroke
				(width 0.1)
				(type default)
			)
			(layer "F.Fab")
		)
		(fp_line
			(start -0.12065 0.2794)
			(end -0.12065 0.3048)
			(stroke
				(width 0.1)
				(type default)
			)
			(layer "F.Fab")
		)
		(fp_line
			(start 0.67945 0.3048)
			(end 0.120396 0.3048)
			(stroke
				(width 0.1)
				(type default)
			)
			(layer "F.Fab")
		)
		(fp_line
			(start 0.120396 0.3048)
			(end 0.120396 0.2794)
			(stroke
				(width 0.1)
				(type default)
			)
			(layer "F.Fab")
		)
		(fp_line
			(start -0.12065 0.3048)
			(end -0.67945 0.3048)
			(stroke
				(width 0.1)
				(type default)
			)
			(layer "F.Fab")
		)
		(fp_line
			(start -0.67945 0.3048)
			(end -0.67945 -0.305054)
			(stroke
				(width 0.1)
				(type default)
			)
			(layer "F.Fab")
		)
		(pad "1" smd rect
			(at -0.40005 0 270)
			(size 0.4572 0.508)
			(layers "F.Cu" "F.Mask" "F.Paste")
			(net "USB2_HUB_SWB_DP")
		)
		(pad "2" smd rect
			(at 0.40005 0 270)
			(size 0.4572 0.508)
			(layers "F.Cu" "F.Mask" "F.Paste")
			(net "USB2_HUB_BUF_SWB_R_DP")
		)
	)
)
